(kicad_pcb
	(version 20260206)
	(generator "pcbnew")
	(generator_version "10.0")
	(general
		(thickness 1.6)
		(legacy_teardrops no)
	)
	(paper "A4")
	(title_block
		(title "fcb — 12433-1M.1206WZS1330.brd")
		(comment 1 "Open Vault / Knox (Wiwynn) / footprints 283-289 of 495")
	)
	(layers
		(0 "F.Cu" signal "TOP")
		(4 "In1.Cu" signal "L2GND")
		(6 "In2.Cu" signal "L3VCC")
		(2 "B.Cu" signal "BOTTOM")
		(9 "F.Adhes" user "F.Adhesive")
		(11 "B.Adhes" user "B.Adhesive")
		(13 "F.Paste" user "Package Geometry/Pastemask Top")
		(15 "B.Paste" user "Package Geometry/Pastemask Bottom")
		(5 "F.SilkS" user "Ref Des/Silkscreen Top")
		(7 "B.SilkS" user "Ref Des/Silkscreen Bottom")
		(1 "F.Mask" user "Board Geometry/Soldermask Top")
		(3 "B.Mask" user "Board Geometry/Soldermask Bottom")
		(17 "Dwgs.User" user "User.Drawings")
		(19 "Cmts.User" user "User.Comments")
		(21 "Eco1.User" user "User.Eco1")
		(23 "Eco2.User" user "User.Eco2")
		(25 "Edge.Cuts" user "Board Geometry/Outline")
		(27 "Margin" user)
		(31 "F.CrtYd" user "Package Geometry/Place Bound Top")
		(29 "B.CrtYd" user "Package Geometry/Place Bound Bottom")
		(35 "F.Fab" user "Ref Des/Assembly Top")
		(33 "B.Fab" user "Ref Des/Assembly Bottom")
	)
	(footprint ""
		(layer "F.Cu")
		(at 30.734 -381 180)
		(property "Reference" "PR20"
			(at 0 0 180)
			(layer "F.SilkS")
			(hide yes)
			(effects
				(font
					(size 1.27 1.27)
				)
			)
		)
		(property "Value" "10R2F-L-GP"
			(at 0.064008 -3.993896 180)
			(unlocked yes)
			(layer "F.Fab")
			(hide yes)
			(effects
				(font
					(size 1.016 1.016)
					(thickness 0.1524)
				)
			)
		)
		(property "Device Type" "R402H14"
			(at 0.064008 -5.517896 180)
			(unlocked yes)
			(layer "F.Fab")
			(hide yes)
			(effects
				(font
					(size 1.016 1.016)
					(thickness 0.1524)
				)
			)
		)
		(duplicate_pad_numbers_are_jumpers no)
		(fp_line
			(start 0.508 -0.9398)
			(end -0.508 -0.9398)
			(stroke
				(width 0.1524)
				(type default)
			)
			(layer "F.SilkS")
		)
		(fp_line
			(start -0.508 -0.9398)
			(end -0.508 0.9398)
			(stroke
				(width 0.1524)
				(type default)
			)
			(layer "F.SilkS")
		)
		(fp_rect
			(start -0.508 0.9398)
			(end 0.508 -0.9398)
			(stroke
				(width 0)
				(type default)
			)
			(fill no)
			(layer "F.CrtYd")
		)
		(fp_rect
			(start -0.508 0.9398)
			(end 0.508 -0.9398)
			(stroke
				(width 0)
				(type default)
			)
			(fill no)
			(layer "F.Fab")
		)
		(pad "1" smd custom
			(at 0 -0.4445 180)
			(size 0.1397 0.1397)
			(layers "F.Cu" "F.Mask" "F.Paste")
			(net "ADM1276_SENSE+")
			(options
				(clearance outline)
				(anchor circle)
			)
			(primitives
				(gr_poly
					(pts
						(arc
							(start -0.1778 -0.2794)
							(mid -0.249642 -0.249642)
							(end -0.2794 -0.1778)
						)
						(arc
							(start -0.2794 0.1778)
							(mid -0.249642 0.249642)
							(end -0.1778 0.2794)
						)
						(arc
							(start 0.1778 0.2794)
							(mid 0.249642 0.249642)
							(end 0.2794 0.1778)
						)
						(arc
							(start 0.2794 -0.1778)
							(mid 0.249642 -0.249642)
							(end 0.1778 -0.2794)
						)
					)
					(width 0)
					(fill yes)
				)
			)
		)
		(pad "2" smd custom
			(at 0 0.4445 180)
			(size 0.1397 0.1397)
			(layers "F.Cu" "F.Mask" "F.Paste")
			(net "SENSE+_R1")
			(options
				(clearance outline)
				(anchor circle)
			)
			(primitives
				(gr_poly
					(pts
						(arc
							(start -0.1778 -0.2794)
							(mid -0.249642 -0.249642)
							(end -0.2794 -0.1778)
						)
						(arc
							(start -0.2794 0.1778)
							(mid -0.249642 0.249642)
							(end -0.1778 0.2794)
						)
						(arc
							(start 0.1778 0.2794)
							(mid 0.249642 0.249642)
							(end 0.2794 0.1778)
						)
						(arc
							(start 0.2794 -0.1778)
							(mid 0.249642 -0.249642)
							(end 0.1778 -0.2794)
						)
					)
					(width 0)
					(fill yes)
				)
			)
		)
	)
	(footprint ""
		(layer "F.Cu")
		(at 37.8968 -139.9794 180)
		(property "Reference" "PU7"
			(at 0 0 180)
			(layer "F.SilkS")
			(hide yes)
			(effects
				(font
					(size 1.27 1.27)
				)
			)
		)
		(property "Value" "TPS2490DGSR-GP"
			(at 0 -11.1252 180)
			(unlocked yes)
			(layer "F.Fab")
			(hide yes)
			(effects
				(font
					(size 1.016 1.016)
					(thickness 0.1524)
				)
			)
		)
		(property "Device Type" "MSOP10H44"
			(at 0 -12.6492 180)
			(unlocked yes)
			(layer "F.Fab")
			(hide yes)
			(effects
				(font
					(size 1.016 1.016)
					(thickness 0.1524)
				)
			)
		)
		(duplicate_pad_numbers_are_jumpers no)
		(fp_line
			(start 1.143 1.016)
			(end -2.0066 1.016)
			(stroke
				(width 0.1524)
				(type default)
			)
			(layer "F.SilkS")
		)
		(fp_line
			(start 1.143 -1.016)
			(end 1.143 1.016)
			(stroke
				(width 0.1524)
				(type default)
			)
			(layer "F.SilkS")
		)
		(fp_line
			(start -1.5748 0)
			(end -1.9558 0.381)
			(stroke
				(width 0.1524)
				(type default)
			)
			(layer "F.SilkS")
		)
		(fp_line
			(start -1.5748 0)
			(end -1.9558 -0.381)
			(stroke
				(width 0.1524)
				(type default)
			)
			(layer "F.SilkS")
		)
		(fp_line
			(start -1.8288 1.016)
			(end -1.8288 3.048)
			(stroke
				(width 0.508)
				(type default)
			)
			(layer "F.SilkS")
		)
		(fp_line
			(start -2.0066 1.016)
			(end -2.0066 -1.016)
			(stroke
				(width 0.1524)
				(type default)
			)
			(layer "F.SilkS")
		)
		(fp_line
			(start -2.0066 -1.016)
			(end 1.143 -1.016)
			(stroke
				(width 0.1524)
				(type default)
			)
			(layer "F.SilkS")
		)
		(fp_poly
			(pts
				(xy -2.0828 3.3401) (xy 2.0828 3.3401) (xy 2.0828 -3.3401) (xy -2.0828 -3.3401)
			)
			(stroke
				(width 0)
				(type default)
			)
			(fill no)
			(layer "F.CrtYd")
		)
		(fp_poly
			(pts
				(xy -2.0828 3.3401) (xy 2.0828 3.3401) (xy 2.0828 -3.3401) (xy -2.0828 -3.3401)
			)
			(stroke
				(width 0)
				(type default)
			)
			(fill no)
			(layer "F.Fab")
		)
		(pad "1" smd rect
			(at -0.99949 2.0701 180)
			(size 0.3048 1.524)
			(layers "F.Cu" "F.Mask" "F.Paste")
			(net "P12VL_2490_EN_2")
		)
		(pad "2" smd rect
			(at -0.50038 2.0701 180)
			(size 0.3048 1.524)
			(layers "F.Cu" "F.Mask" "F.Paste")
			(net "P12VL_2490_VREF")
		)
		(pad "3" smd rect
			(at 0 2.0701 180)
			(size 0.3048 1.524)
			(layers "F.Cu" "F.Mask" "F.Paste")
			(net "P12VL_2490_PROG")
		)
		(pad "4" smd rect
			(at 0.50038 2.0701 180)
			(size 0.3048 1.524)
			(layers "F.Cu" "F.Mask" "F.Paste")
			(net "P12VL_2490_TIMER")
		)
		(pad "5" smd rect
			(at 0.99949 2.0701 180)
			(size 0.3048 1.524)
			(layers "F.Cu" "F.Mask" "F.Paste")
			(net "GND")
		)
		(pad "6" smd rect
			(at 0.99949 -2.0701 180)
			(size 0.3048 1.524)
			(layers "F.Cu" "F.Mask" "F.Paste")
			(net "P12VL_2490_PG")
		)
		(pad "7" smd rect
			(at 0.50038 -2.0701 180)
			(size 0.3048 1.524)
			(layers "F.Cu" "F.Mask" "F.Paste")
			(net "P12VL")
		)
		(pad "8" smd rect
			(at 0 -2.0701 180)
			(size 0.3048 1.524)
			(layers "F.Cu" "F.Mask" "F.Paste")
			(net "P12VL_2490_GATE")
		)
		(pad "9" smd rect
			(at -0.50038 -2.0701 180)
			(size 0.3048 1.524)
			(layers "F.Cu" "F.Mask" "F.Paste")
			(net "P12VL_2490_SENSE")
		)
		(pad "10" smd rect
			(at -0.99949 -2.0701 180)
			(size 0.3048 1.524)
			(layers "F.Cu" "F.Mask" "F.Paste")
			(net "P12VL_2490_VCC")
		)
	)
	(footprint ""
		(layer "F.Cu")
		(at 33.51149 -152.889966 180)
		(property "Reference" "TP10"
			(at 0 0 180)
			(layer "F.SilkS")
			(hide yes)
			(effects
				(font
					(size 1.27 1.27)
				)
			)
		)
		(property "Value" "TPAD32-GP"
			(at 0 -3.166364 180)
			(unlocked yes)
			(layer "F.Fab")
			(hide yes)
			(effects
				(font
					(size 1.016 1.016)
					(thickness 0.1524)
				)
			)
		)
		(property "Device Type" "TPAD32"
			(at 0 -4.690618 180)
			(unlocked yes)
			(layer "F.Fab")
			(hide yes)
			(effects
				(font
					(size 1.016 1.016)
					(thickness 0.1524)
				)
			)
		)
		(duplicate_pad_numbers_are_jumpers no)
		(fp_poly
			(pts
				(arc
					(start 0.7112 0)
					(mid -0.7112 0)
					(end 0.7112 0)
				)
			)
			(stroke
				(width 0)
				(type default)
			)
			(fill no)
			(layer "F.CrtYd")
		)
		(fp_poly
			(pts
				(arc
					(start 0.7112 0)
					(mid -0.7112 0)
					(end 0.7112 0)
				)
			)
			(stroke
				(width 0)
				(type default)
			)
			(fill no)
			(layer "F.Fab")
		)
		(pad "1" smd circle
			(at 0 0 180)
			(size 0.8128 0.8128)
			(layers "F.Cu" "F.Mask" "F.Paste")
			(net "NCT7904_VSEN11")
		)
	)
	(footprint ""
		(layer "F.Cu")
		(at 20.675092 -285.598362 180)
		(property "Reference" "R94"
			(at 0 0 180)
			(layer "F.SilkS")
			(hide yes)
			(effects
				(font
					(size 1.27 1.27)
				)
			)
		)
		(property "Value" "4K7R2F-GP"
			(at 0.064008 -3.993896 180)
			(unlocked yes)
			(layer "F.Fab")
			(hide yes)
			(effects
				(font
					(size 1.016 1.016)
					(thickness 0.1524)
				)
			)
		)
		(property "Device Type" "R402H16"
			(at 0.064008 -5.517896 180)
			(unlocked yes)
			(layer "F.Fab")
			(hide yes)
			(effects
				(font
					(size 1.016 1.016)
					(thickness 0.1524)
				)
			)
		)
		(duplicate_pad_numbers_are_jumpers no)
		(fp_line
			(start 0.508 -0.9398)
			(end -0.508 -0.9398)
			(stroke
				(width 0.1524)
				(type default)
			)
			(layer "F.SilkS")
		)
		(fp_line
			(start -0.508 -0.9398)
			(end -0.508 0.9398)
			(stroke
				(width 0.1524)
				(type default)
			)
			(layer "F.SilkS")
		)
		(fp_rect
			(start -0.508 0.9398)
			(end 0.508 -0.9398)
			(stroke
				(width 0)
				(type default)
			)
			(fill no)
			(layer "F.CrtYd")
		)
		(fp_rect
			(start -0.508 0.9398)
			(end 0.508 -0.9398)
			(stroke
				(width 0)
				(type default)
			)
			(fill no)
			(layer "F.Fab")
		)
		(pad "1" smd custom
			(at 0 -0.4445 180)
			(size 0.1397 0.1397)
			(layers "F.Cu" "F.Mask" "F.Paste")
			(net "P12V")
			(options
				(clearance outline)
				(anchor circle)
			)
			(primitives
				(gr_poly
					(pts
						(arc
							(start -0.1778 -0.2794)
							(mid -0.249642 -0.249642)
							(end -0.2794 -0.1778)
						)
						(arc
							(start -0.2794 0.1778)
							(mid -0.249642 0.249642)
							(end -0.1778 0.2794)
						)
						(arc
							(start 0.1778 0.2794)
							(mid 0.249642 0.249642)
							(end 0.2794 0.1778)
						)
						(arc
							(start 0.2794 -0.1778)
							(mid 0.249642 -0.249642)
							(end 0.1778 -0.2794)
						)
					)
					(width 0)
					(fill yes)
				)
			)
		)
		(pad "2" smd custom
			(at 0 0.4445 180)
			(size 0.1397 0.1397)
			(layers "F.Cu" "F.Mask" "F.Paste")
			(net "FAN_TACH4")
			(options
				(clearance outline)
				(anchor circle)
			)
			(primitives
				(gr_poly
					(pts
						(arc
							(start -0.1778 -0.2794)
							(mid -0.249642 -0.249642)
							(end -0.2794 -0.1778)
						)
						(arc
							(start -0.2794 0.1778)
							(mid -0.249642 0.249642)
							(end -0.1778 0.2794)
						)
						(arc
							(start 0.1778 0.2794)
							(mid 0.249642 0.249642)
							(end 0.2794 0.1778)
						)
						(arc
							(start 0.2794 -0.1778)
							(mid 0.249642 -0.249642)
							(end 0.1778 -0.2794)
						)
					)
					(width 0)
					(fill yes)
				)
			)
		)
	)
	(footprint ""
		(layer "F.Cu")
		(at 37.719 -352.425 90)
		(property "Reference" "C261"
			(at 0 0 90)
			(layer "F.SilkS")
			(hide yes)
			(effects
				(font
					(size 1.27 1.27)
				)
			)
		)
		(property "Value" "SC10U25V6KX-1GP"
			(at -0.0762 -5.1308 90)
			(unlocked yes)
			(layer "F.Fab")
			(hide yes)
			(effects
				(font
					(size 1.016 1.016)
					(thickness 0.1524)
				)
			)
		)
		(property "Device Type" "C1206H71"
			(at -0.127 -6.6548 90)
			(unlocked yes)
			(layer "F.Fab")
			(hide yes)
			(effects
				(font
					(size 1.016 1.016)
					(thickness 0.1524)
				)
			)
		)
		(duplicate_pad_numbers_are_jumpers no)
		(fp_line
			(start 1.016 -2.2352)
			(end 1.016 -0.8382)
			(stroke
				(width 0.1524)
				(type default)
			)
			(layer "F.SilkS")
		)
		(fp_line
			(start -1.016 -2.2352)
			(end 1.016 -2.2352)
			(stroke
				(width 0.1524)
				(type default)
			)
			(layer "F.SilkS")
		)
		(fp_line
			(start -1.016 -0.8382)
			(end -1.016 -2.2352)
			(stroke
				(width 0.1524)
				(type default)
			)
			(layer "F.SilkS")
		)
		(fp_line
			(start 1.016 0.8382)
			(end 1.016 2.2352)
			(stroke
				(width 0.1524)
				(type default)
			)
			(layer "F.SilkS")
		)
		(fp_line
			(start 1.016 2.2352)
			(end -1.016 2.2352)
			(stroke
				(width 0.1524)
				(type default)
			)
			(layer "F.SilkS")
		)
		(fp_line
			(start -1.016 2.2352)
			(end -1.016 0.8382)
			(stroke
				(width 0.1524)
				(type default)
			)
			(layer "F.SilkS")
		)
		(fp_rect
			(start -1.0922 2.3114)
			(end 1.0922 -2.3114)
			(stroke
				(width 0)
				(type default)
			)
			(fill no)
			(layer "F.CrtYd")
		)
		(fp_poly
			(pts
				(xy 1.0922 -2.3114) (xy 1.0922 2.3114) (xy -1.0922 2.3114) (xy -1.0922 -2.3114)
			)
			(stroke
				(width 0)
				(type default)
			)
			(fill no)
			(layer "F.Fab")
		)
		(pad "1" smd rect
			(at 0 -1.397 90)
			(size 1.651 1.27)
			(layers "F.Cu" "F.Mask" "F.Paste")
			(net "OTP_RETRY_G")
		)
		(pad "2" smd rect
			(at 0 1.397 90)
			(size 1.651 1.27)
			(layers "F.Cu" "F.Mask" "F.Paste")
			(net "GND")
		)
	)
	(footprint ""
		(layer "F.Cu")
		(at 16.3068 -254.3302 180)
		(property "Reference" "R86"
			(at 0 0 180)
			(layer "F.SilkS")
			(hide yes)
			(effects
				(font
					(size 1.27 1.27)
				)
			)
		)
		(property "Value" "27KR3F-GP"
			(at -0.0254 -2.5146 180)
			(unlocked yes)
			(layer "F.Fab")
			(hide yes)
			(effects
				(font
					(size 1.016 1.016)
					(thickness 0.1524)
				)
			)
		)
		(property "Device Type" "R603H22"
			(at -0.0254 -4.0386 180)
			(unlocked yes)
			(layer "F.Fab")
			(hide yes)
			(effects
				(font
					(size 1.016 1.016)
					(thickness 0.1524)
				)
			)
		)
		(duplicate_pad_numbers_are_jumpers no)
		(fp_line
			(start 0.2032 0)
			(end 0.4826 0)
			(stroke
				(width 0.2032)
				(type default)
			)
			(layer "F.SilkS")
		)
		(fp_line
			(start -0.4826 0)
			(end -0.2032 0)
			(stroke
				(width 0.2032)
				(type default)
			)
			(layer "F.SilkS")
		)
		(fp_rect
			(start -0.5842 1.3335)
			(end 0.5842 -1.3335)
			(stroke
				(width 0)
				(type default)
			)
			(fill no)
			(layer "F.CrtYd")
		)
		(fp_rect
			(start -0.5842 1.3335)
			(end 0.5842 -1.3335)
			(stroke
				(width 0)
				(type default)
			)
			(fill no)
			(layer "F.Fab")
		)
		(pad "1" smd custom
			(at 0 -0.762 180)
			(size 0.2159 0.2159)
			(layers "F.Cu" "F.Mask" "F.Paste")
			(net "FANIN_5")
			(options
				(clearance outline)
				(anchor circle)
			)
			(primitives
				(gr_poly
					(pts
						(arc
							(start -0.3302 -0.4318)
							(mid -0.402042 -0.402042)
							(end -0.4318 -0.3302)
						)
						(arc
							(start -0.4318 0.3302)
							(mid -0.402042 0.402042)
							(end -0.3302 0.4318)
						)
						(arc
							(start 0.3302 0.4318)
							(mid 0.402042 0.402042)
							(end 0.4318 0.3302)
						)
						(arc
							(start 0.4318 -0.3302)
							(mid 0.402042 -0.402042)
							(end 0.3302 -0.4318)
						)
					)
					(width 0)
					(fill yes)
				)
			)
		)
		(pad "2" smd custom
			(at 0 0.762 180)
			(size 0.2159 0.2159)
			(layers "F.Cu" "F.Mask" "F.Paste")
			(net "FAN_TACH5")
			(options
				(clearance outline)
				(anchor circle)
			)
			(primitives
				(gr_poly
					(pts
						(arc
							(start -0.3302 -0.4318)
							(mid -0.402042 -0.402042)
							(end -0.4318 -0.3302)
						)
						(arc
							(start -0.4318 0.3302)
							(mid -0.402042 0.402042)
							(end -0.3302 0.4318)
						)
						(arc
							(start 0.3302 0.4318)
							(mid 0.402042 0.402042)
							(end 0.4318 0.3302)
						)
						(arc
							(start 0.4318 -0.3302)
							(mid 0.402042 -0.402042)
							(end 0.3302 -0.4318)
						)
					)
					(width 0)
					(fill yes)
				)
			)
		)
	)
	(footprint ""
		(layer "F.Cu")
		(at 31.7246 -149.073616)
		(property "Reference" "R128"
			(at 0 0 0)
			(layer "F.SilkS")
			(hide yes)
			(effects
				(font
					(size 1.27 1.27)
				)
			)
		)
		(property "Value" "10KR2F-2-GP"
			(at 0.064008 -3.993896 0)
			(unlocked yes)
			(layer "F.Fab")
			(hide yes)
			(effects
				(font
					(size 1.016 1.016)
					(thickness 0.1524)
				)
			)
		)
		(property "Device Type" "R402H16"
			(at 0.064008 -5.517896 0)
			(unlocked yes)
			(layer "F.Fab")
			(hide yes)
			(effects
				(font
					(size 1.016 1.016)
					(thickness 0.1524)
				)
			)
		)
		(duplicate_pad_numbers_are_jumpers no)
		(fp_line
			(start -0.508 -0.9398)
			(end -0.508 0.9398)
			(stroke
				(width 0.1524)
				(type default)
			)
			(layer "F.SilkS")
		)
		(fp_line
			(start 0.508 -0.9398)
			(end -0.508 -0.9398)
			(stroke
				(width 0.1524)
				(type default)
			)
			(layer "F.SilkS")
		)
		(fp_rect
			(start -0.508 0.9398)
			(end 0.508 -0.9398)
			(stroke
				(width 0)
				(type default)
			)
			(fill no)
			(layer "F.CrtYd")
		)
		(fp_rect
			(start -0.508 0.9398)
			(end 0.508 -0.9398)
			(stroke
				(width 0)
				(type default)
			)
			(fill no)
			(layer "F.Fab")
		)
		(pad "1" smd custom
			(at 0 -0.4445)
			(size 0.1397 0.1397)
			(layers "F.Cu" "F.Mask" "F.Paste")
			(net "NCT7904_VSEN7")
			(options
				(clearance outline)
				(anchor circle)
			)
			(primitives
				(gr_poly
					(pts
						(arc
							(start -0.1778 -0.2794)
							(mid -0.249642 -0.249642)
							(end -0.2794 -0.1778)
						)
						(arc
							(start -0.2794 0.1778)
							(mid -0.249642 0.249642)
							(end -0.1778 0.2794)
						)
						(arc
							(start 0.1778 0.2794)
							(mid 0.249642 0.249642)
							(end 0.2794 0.1778)
						)
						(arc
							(start 0.2794 -0.1778)
							(mid 0.249642 -0.249642)
							(end 0.1778 -0.2794)
						)
					)
					(width 0)
					(fill yes)
				)
			)
		)
		(pad "2" smd custom
			(at 0 0.4445)
			(size 0.1397 0.1397)
			(layers "F.Cu" "F.Mask" "F.Paste")
			(net "GND")
			(options
				(clearance outline)
				(anchor circle)
			)
			(primitives
				(gr_poly
					(pts
						(arc
							(start -0.1778 -0.2794)
							(mid -0.249642 -0.249642)
							(end -0.2794 -0.1778)
						)
						(arc
							(start -0.2794 0.1778)
							(mid -0.249642 0.249642)
							(end -0.1778 0.2794)
						)
						(arc
							(start 0.1778 0.2794)
							(mid 0.249642 0.249642)
							(end 0.2794 0.1778)
						)
						(arc
							(start 0.2794 -0.1778)
							(mid 0.249642 -0.249642)
							(end 0.1778 -0.2794)
						)
					)
					(width 0)
					(fill yes)
				)
			)
		)
	)
)
